(kicad_pcb
	(version 20260206)
	(generator "pcbnew")
	(generator_version "10.0")
	(general
		(thickness 1.21888)
		(legacy_teardrops no)
	)
	(paper "A4")
	(title_block
		(title "timecard-v8 — TimeCard-DC-V8_EXP.PcbDoc")
		(comment 1 "Time Appliance Project (Time Card) / footprints 272-282 of 288")
	)
	(layers
		(0 "F.Cu" signal "TOP")
		(4 "In1.Cu" signal "SGND")
		(6 "In2.Cu" signal "IN1")
		(8 "In3.Cu" signal "IN2")
		(10 "In4.Cu" signal "SGND1")
		(2 "B.Cu" signal "BOTTOM")
		(9 "F.Adhes" user "F.Adhesive")
		(11 "B.Adhes" user "B.Adhesive")
		(13 "F.Paste" user "Top Paste")
		(15 "B.Paste" user "Bottom Paste")
		(5 "F.SilkS" user "Top Overlay")
		(7 "B.SilkS" user "Bottom Overlay")
		(1 "F.Mask" user "Top Solder")
		(3 "B.Mask" user "Bottom Solder")
		(17 "Dwgs.User" user "User.Drawings")
		(19 "Cmts.User" user "User.Comments")
		(21 "Eco1.User" user "User.Eco1")
		(23 "Eco2.User" user "User.Eco2")
		(25 "Edge.Cuts" user)
		(27 "Margin" user)
		(31 "F.CrtYd" user "Top Courtyard")
		(29 "B.CrtYd" user "Bottom Courtyard")
		(35 "F.Fab" user "Top Component Center")
		(33 "B.Fab" user "Bottom Component Center")
	)
	(footprint "Vault:RESC1005X40X25NL05T05"
		(layer "F.Cu")
		(at 222.5261 77.1162 180)
		(property "Reference" "R84"
			(at -0.2286 1.373079 0)
			(unlocked yes)
			(layer "F.SilkS")
			(effects
				(font
					(size 0.762 0.762)
					(thickness 0.2286)
				)
			)
		)
		(property "Value" "27_1%_0402"
			(at -2.732271 7.37632 90)
			(unlocked yes)
			(layer "F.SilkS")
			(hide yes)
			(effects
				(font
					(size 0.762 0.762)
					(thickness 0.2286)
				)
			)
		)
		(sheetname "USBUart_DipSelects")
		(sheetfile "USBUart_DipSelects.kicad_sch")
		(duplicate_pad_numbers_are_jumpers no)
		(pad "1" smd rect
			(at -0.45 0 270)
			(size 0.55 0.55)
			(layers "F.Cu" "F.Mask" "F.Paste")
			(net "GND")
		)
		(pad "2" smd rect
			(at 0.45 0 270)
			(size 0.55 0.55)
			(layers "F.Cu" "F.Mask" "F.Paste")
			(net "NetR84_2")
		)
	)
	(footprint "Vault:FP-DFN-12-IPC_B"
		(layer "F.Cu")
		(at 237.2261 68.6162 90)
		(property "Reference" "U20"
			(at -1.0286 2.573069 270)
			(unlocked yes)
			(layer "F.SilkS")
			(effects
				(font
					(size 0.762 0.762)
					(thickness 0.2286)
				)
			)
		)
		(property "Value" "FT234XD-R"
			(at 4.45556 3.392671 90)
			(unlocked yes)
			(layer "F.SilkS")
			(hide yes)
			(effects
				(font
					(size 0.762 0.762)
					(thickness 0.2286)
				)
			)
		)
		(sheetname "USBUart_DipSelects")
		(sheetfile "USBUart_DipSelects.kicad_sch")
		(duplicate_pad_numbers_are_jumpers no)
		(fp_line
			(start -1.5 -1.625)
			(end 1.5 -1.625)
			(stroke
				(width 0.2)
				(type solid)
			)
			(layer "F.SilkS")
		)
		(fp_line
			(start -1.5 1.625)
			(end 1.5 1.625)
			(stroke
				(width 0.2)
				(type solid)
			)
			(layer "F.SilkS")
		)
		(fp_circle
			(center -2.38536 -1.125)
			(end -2.26036 -1.125)
			(stroke
				(width 0.25)
				(type solid)
			)
			(fill no)
			(layer "F.SilkS")
		)
		(fp_rect
			(start -0.461505 0.911635)
			(end 0.461635 -0.911495)
			(stroke
				(width 0)
				(type default)
			)
			(fill yes)
			(layer "F.Paste")
		)
		(fp_line
			(start 2.08535 -1.75)
			(end 2.08535 1.75)
			(stroke
				(width 0.2)
				(type solid)
			)
			(layer "F.CrtYd")
		)
		(fp_line
			(start -2.08536 -1.75)
			(end 2.08535 -1.75)
			(stroke
				(width 0.2)
				(type solid)
			)
			(layer "F.CrtYd")
		)
		(fp_line
			(start -2.08536 -1.75)
			(end -2.08536 1.75)
			(stroke
				(width 0.2)
				(type solid)
			)
			(layer "F.CrtYd")
		)
		(fp_line
			(start -2.08536 1.75)
			(end 2.08535 1.75)
			(stroke
				(width 0.2)
				(type solid)
			)
			(layer "F.CrtYd")
		)
		(fp_line
			(start 2.08535 -1.75)
			(end 2.08535 1.75)
			(stroke
				(width 0.2)
				(type solid)
			)
			(layer "F.Fab")
		)
		(fp_line
			(start -2.08536 -1.75)
			(end 2.08535 -1.75)
			(stroke
				(width 0.2)
				(type solid)
			)
			(layer "F.Fab")
		)
		(fp_line
			(start -2.08536 -1.75)
			(end -2.08536 1.75)
			(stroke
				(width 0.2)
				(type solid)
			)
			(layer "F.Fab")
		)
		(fp_line
			(start 0 -0.5)
			(end 0 0.5)
			(stroke
				(width 0.1)
				(type solid)
			)
			(layer "F.Fab")
		)
		(fp_line
			(start -0.5 0)
			(end 0.5 0)
			(stroke
				(width 0.1)
				(type solid)
			)
			(layer "F.Fab")
		)
		(fp_line
			(start -2.08536 1.75)
			(end 2.08535 1.75)
			(stroke
				(width 0.2)
				(type solid)
			)
			(layer "F.Fab")
		)
		(fp_text user "${REFERENCE}"
			(at 0 0.28425 90)
			(unlocked yes)
			(layer "F.Fab")
			(effects
				(font
					(face "Arial")
					(size 0.63 0.63)
					(thickness 0.1)
				)
				(justify left bottom)
			)
		)
		(pad "1" smd rect
			(at -1.4155 -1.125 90)
			(size 0.83971 0.22247)
			(layers "F.Cu" "F.Mask" "F.Paste")
			(net "FTDI_USB_N")
			(solder_mask_margin 0)
			(solder_paste_margin 0)
		)
		(pad "2" smd roundrect
			(at -1.4155 -0.675 90)
			(size 0.83971 0.22247)
			(layers "F.Cu" "F.Mask" "F.Paste")
			(roundrect_rratio 0.5)
			(net "NetC91_1")
			(solder_mask_margin 0)
			(solder_paste_margin 0)
		)
		(pad "3" smd roundrect
			(at -1.4155 -0.225 90)
			(size 0.83971 0.22247)
			(layers "F.Cu" "F.Mask" "F.Paste")
			(roundrect_rratio 0.5)
			(net "NetC92_1")
			(solder_mask_margin 0)
			(solder_paste_margin 0)
		)
		(pad "4" smd roundrect
			(at -1.4155 0.225 90)
			(size 0.83971 0.22247)
			(layers "F.Cu" "F.Mask" "F.Paste")
			(roundrect_rratio 0.5)
			(net "FTDI_VBUS")
			(solder_mask_margin 0)
			(solder_paste_margin 0)
		)
		(pad "5" smd roundrect
			(at -1.4155 0.675 90)
			(size 0.83971 0.22247)
			(layers "F.Cu" "F.Mask" "F.Paste")
			(roundrect_rratio 0.5)
			(net "GND")
			(solder_mask_margin 0)
			(solder_paste_margin 0)
		)
		(pad "6" smd roundrect
			(at -1.4155 1.125 90)
			(size 0.83971 0.22247)
			(layers "F.Cu" "F.Mask" "F.Paste")
			(roundrect_rratio 0.5)
			(solder_mask_margin 0)
			(solder_paste_margin 0)
		)
		(pad "7" smd roundrect
			(at 1.4155 1.125 90)
			(size 0.83971 0.22247)
			(layers "F.Cu" "F.Mask" "F.Paste")
			(roundrect_rratio 0.5)
			(net "NetR13_1")
			(solder_mask_margin 0)
			(solder_paste_margin 0)
		)
		(pad "8" smd roundrect
			(at 1.4155 0.675 90)
			(size 0.83971 0.22247)
			(layers "F.Cu" "F.Mask" "F.Paste")
			(roundrect_rratio 0.5)
			(solder_mask_margin 0)
			(solder_paste_margin 0)
		)
		(pad "9" smd roundrect
			(at 1.4155 0.225 90)
			(size 0.83971 0.22247)
			(layers "F.Cu" "F.Mask" "F.Paste")
			(roundrect_rratio 0.5)
			(net "NetC92_1")
			(solder_mask_margin 0)
			(solder_paste_margin 0)
		)
		(pad "10" smd roundrect
			(at 1.4155 -0.225 90)
			(size 0.83971 0.22247)
			(layers "F.Cu" "F.Mask" "F.Paste")
			(roundrect_rratio 0.5)
			(net "NetR42_1")
			(solder_mask_margin 0)
			(solder_paste_margin 0)
		)
		(pad "11" smd roundrect
			(at 1.4155 -0.675 90)
			(size 0.83971 0.22247)
			(layers "F.Cu" "F.Mask" "F.Paste")
			(roundrect_rratio 0.5)
			(solder_mask_margin 0)
			(solder_paste_margin 0)
		)
		(pad "12" smd roundrect
			(at 1.4155 -1.125 90)
			(size 0.83971 0.22247)
			(layers "F.Cu" "F.Mask" "F.Paste")
			(roundrect_rratio 0.5)
			(net "FTDI_USB_P")
			(solder_mask_margin 0)
			(solder_paste_margin 0)
		)
		(pad "13" smd rect
			(at 0 0 90)
			(size 1.65 2.55)
			(layers "F.Cu" "F.Mask" "F.Paste")
			(net "GND")
			(solder_mask_margin 0)
			(solder_paste_margin -1000)
		)
	)
	(footprint "Vault:RESC1005X40X25LL05T05"
		(layer "F.Cu")
		(at 183.6261 89.3162)
		(property "Reference" "R50"
			(at 0.2286 1.126931 0)
			(unlocked yes)
			(layer "F.SilkS")
			(effects
				(font
					(size 0.762 0.762)
					(thickness 0.2286)
				)
			)
		)
		(property "Value" "4.7K_0402"
			(at -3.024391 2.374045 270)
			(unlocked yes)
			(layer "F.SilkS")
			(hide yes)
			(effects
				(font
					(size 0.762 0.762)
					(thickness 0.2286)
				)
			)
		)
		(sheetname "GPS_IMU_SENSORS")
		(sheetfile "GPS_IMU_SENSORS.kicad_sch")
		(duplicate_pad_numbers_are_jumpers no)
		(pad "1" smd rect
			(at -0.4 0 90)
			(size 0.45 0.45)
			(layers "F.Cu" "F.Mask" "F.Paste")
			(net "+3.3V")
		)
		(pad "2" smd rect
			(at 0.4 0 90)
			(size 0.45 0.45)
			(layers "F.Cu" "F.Mask" "F.Paste")
			(net "BNO_INT")
		)
	)
	(footprint "Vault:TECO-1909763-1_V"
		(layer "F.Cu")
		(at 74.3761 135.6162 -90)
		(property "Reference" "J4"
			(at -2.723079 1.021395 0)
			(unlocked yes)
			(layer "F.SilkS")
			(effects
				(font
					(size 0.762 0.762)
					(thickness 0.2286)
				)
			)
		)
		(property "Value" "1909763-1"
			(at 4.582685 3.722871 270)
			(unlocked yes)
			(layer "F.SilkS")
			(hide yes)
			(effects
				(font
					(size 0.762 0.762)
					(thickness 0.2286)
				)
			)
		)
		(sheetname "USER_IO")
		(sheetfile "USER_IO.kicad_sch")
		(duplicate_pad_numbers_are_jumpers no)
		(fp_line
			(start 0.55 -1.3)
			(end -0.55 -1.3)
			(stroke
				(width 0.2)
				(type solid)
			)
			(layer "F.SilkS")
		)
		(fp_circle
			(center -1.778 1.65)
			(end -1.903 1.65)
			(stroke
				(width 0.25)
				(type solid)
			)
			(fill no)
			(layer "F.SilkS")
		)
		(pad "1" smd rect
			(at -1.475 0 270)
			(size 1.05 2.2)
			(layers "F.Cu" "F.Mask" "F.Paste")
			(net "GND")
		)
		(pad "2" smd rect
			(at 0 1.525 270)
			(size 1 1.05)
			(layers "F.Cu" "F.Mask" "F.Paste")
			(net "NetAN4_1")
		)
		(pad "3" smd rect
			(at 1.475 0 270)
			(size 1.05 2.2)
			(layers "F.Cu" "F.Mask" "F.Paste")
			(net "GND")
		)
	)
	(footprint "Vault:FP-MK212BG-MFG"
		(layer "F.Cu")
		(at 85.8761 79.0786 -90)
		(property "Reference" "C60"
			(at 1.5 -4.593345 90)
			(unlocked yes)
			(layer "F.SilkS")
			(effects
				(font
					(size 0.762 0.762)
					(thickness 0.2286)
				)
				(justify left bottom)
			)
		)
		(property "Value" "10uF"
			(at 3.433445 1.5875 0)
			(unlocked yes)
			(layer "F.SilkS")
			(hide yes)
			(effects
				(font
					(size 0.762 0.762)
					(thickness 0.2286)
				)
				(justify left bottom)
			)
		)
		(sheetname "GPS_IMU_SENSORS")
		(sheetfile "GPS_IMU_SENSORS.kicad_sch")
		(duplicate_pad_numbers_are_jumpers no)
		(fp_line
			(start 0.125 0.725)
			(end -0.125 0.725)
			(stroke
				(width 0.2)
				(type solid)
			)
			(layer "F.SilkS")
		)
		(fp_line
			(start 0.125 -0.725)
			(end -0.125 -0.725)
			(stroke
				(width 0.2)
				(type solid)
			)
			(layer "F.SilkS")
		)
		(fp_line
			(start -1.6 0.825)
			(end -1.6 -0.825)
			(stroke
				(width 0.2)
				(type solid)
			)
			(layer "F.CrtYd")
		)
		(fp_line
			(start 1.6 0.825)
			(end -1.6 0.825)
			(stroke
				(width 0.2)
				(type solid)
			)
			(layer "F.CrtYd")
		)
		(fp_line
			(start 1.6 0.825)
			(end 1.6 -0.825)
			(stroke
				(width 0.2)
				(type solid)
			)
			(layer "F.CrtYd")
		)
		(fp_line
			(start 1.6 -0.825)
			(end -1.6 -0.825)
			(stroke
				(width 0.2)
				(type solid)
			)
			(layer "F.CrtYd")
		)
		(fp_line
			(start -1.6 0.825)
			(end -1.6 -0.825)
			(stroke
				(width 0.2)
				(type solid)
			)
			(layer "F.Fab")
		)
		(fp_line
			(start 1.6 0.825)
			(end -1.6 0.825)
			(stroke
				(width 0.2)
				(type solid)
			)
			(layer "F.Fab")
		)
		(fp_line
			(start 1.6 0.825)
			(end 1.6 -0.825)
			(stroke
				(width 0.2)
				(type solid)
			)
			(layer "F.Fab")
		)
		(fp_line
			(start 0 0.5)
			(end 0 -0.5)
			(stroke
				(width 0.1)
				(type solid)
			)
			(layer "F.Fab")
		)
		(fp_line
			(start 0.5 0)
			(end -0.5 0)
			(stroke
				(width 0.1)
				(type solid)
			)
			(layer "F.Fab")
		)
		(fp_line
			(start 1.6 -0.825)
			(end -1.6 -0.825)
			(stroke
				(width 0.2)
				(type solid)
			)
			(layer "F.Fab")
		)
		(fp_text user "${REFERENCE}"
			(at -0.00001 0.09601 270)
			(unlocked yes)
			(layer "F.Fab")
			(effects
				(font
					(face "Arial")
					(size 0.63 0.63)
					(thickness 0.1)
				)
				(justify left bottom)
			)
		)
		(pad "1" smd rect
			(at -1 0 270)
			(size 1 1.25)
			(layers "F.Cu" "F.Mask" "F.Paste")
			(net "+5.0V")
			(solder_mask_margin 0)
			(solder_paste_margin 0)
		)
		(pad "2" smd rect
			(at 1 0 270)
			(size 1 1.25)
			(layers "F.Cu" "F.Mask" "F.Paste")
			(net "GND")
			(solder_mask_margin 0)
			(solder_paste_margin 0)
		)
	)
	(footprint "Vault:FP-SML-LX0603IW-TR-MFG"
		(layer "F.Cu")
		(at 234.0261 137.2162 180)
		(property "Reference" "D4"
			(at 1.3 -2.093345 0)
			(unlocked yes)
			(layer "F.SilkS")
			(effects
				(font
					(size 0.762 0.762)
					(thickness 0.2286)
				)
				(justify left bottom)
			)
		)
		(property "Value" "SML-LX0603IW-TR"
			(at 18.2973 -9.341045 0)
			(unlocked yes)
			(layer "F.SilkS")
			(hide yes)
			(effects
				(font
					(size 0.762 0.762)
					(thickness 0.2286)
				)
				(justify left bottom)
			)
		)
		(sheetname "POWER")
		(sheetfile "POWER.kicad_sch")
		(duplicate_pad_numbers_are_jumpers no)
		(fp_line
			(start 0.8 -0.75)
			(end -0.8 -0.75)
			(stroke
				(width 0.2)
				(type solid)
			)
			(layer "F.SilkS")
		)
		(fp_line
			(start 0.77933 0.73)
			(end -0.82067 0.73)
			(stroke
				(width 0.2)
				(type solid)
			)
			(layer "F.SilkS")
		)
		(fp_circle
			(center -1.725 0)
			(end -1.725 0.125)
			(stroke
				(width 0.25)
				(type solid)
			)
			(fill no)
			(layer "F.SilkS")
		)
		(fp_line
			(start 1.25 0.625)
			(end -1.25 0.625)
			(stroke
				(width 0.2)
				(type solid)
			)
			(layer "F.CrtYd")
		)
		(fp_line
			(start 1.25 -0.625)
			(end 1.25 0.625)
			(stroke
				(width 0.2)
				(type solid)
			)
			(layer "F.CrtYd")
		)
		(fp_line
			(start 1.25 -0.625)
			(end -1.25 -0.625)
			(stroke
				(width 0.2)
				(type solid)
			)
			(layer "F.CrtYd")
		)
		(fp_line
			(start -1.25 -0.625)
			(end -1.25 0.625)
			(stroke
				(width 0.2)
				(type solid)
			)
			(layer "F.CrtYd")
		)
		(fp_line
			(start 1.25 0.625)
			(end -1.25 0.625)
			(stroke
				(width 0.2)
				(type solid)
			)
			(layer "F.Fab")
		)
		(fp_line
			(start 1.25 -0.625)
			(end 1.25 0.625)
			(stroke
				(width 0.2)
				(type solid)
			)
			(layer "F.Fab")
		)
		(fp_line
			(start 1.25 -0.625)
			(end -1.25 -0.625)
			(stroke
				(width 0.2)
				(type solid)
			)
			(layer "F.Fab")
		)
		(fp_line
			(start 0.5 0)
			(end -0.5 0)
			(stroke
				(width 0.1)
				(type solid)
			)
			(layer "F.Fab")
		)
		(fp_line
			(start 0 -0.5)
			(end 0 0.5)
			(stroke
				(width 0.1)
				(type solid)
			)
			(layer "F.Fab")
		)
		(fp_line
			(start -1.25 -0.625)
			(end -1.25 0.625)
			(stroke
				(width 0.2)
				(type solid)
			)
			(layer "F.Fab")
		)
		(fp_text user "${REFERENCE}"
			(at 0 0.29534 180)
			(unlocked yes)
			(layer "F.Fab")
			(effects
				(font
					(face "Arial")
					(size 0.63 0.63)
					(thickness 0.1)
				)
				(justify left bottom)
			)
		)
		(pad "1" smd rect
			(at -0.75 0 180)
			(size 0.8 0.8)
			(layers "F.Cu" "F.Mask" "F.Paste")
			(net "NetD4_1")
			(solder_mask_margin 0)
			(solder_paste_margin 0)
		)
		(pad "2" smd rect
			(at 0.75 0 180)
			(size 0.8 0.8)
			(layers "F.Cu" "F.Mask" "F.Paste")
			(net "+5.0V")
			(solder_mask_margin 0)
			(solder_paste_margin 0)
		)
	)
	(footprint "Vault:RESC1005X40X25LL05T05"
		(layer "F.Cu")
		(at 202.9261 123.9162)
		(property "Reference" "R68"
			(at -3.1714 4.126921 0)
			(unlocked yes)
			(layer "F.SilkS")
			(effects
				(font
					(size 0.762 0.762)
					(thickness 0.2286)
				)
			)
		)
		(property "Value" "4.7K_0402"
			(at -2.389351 6.538405 270)
			(unlocked yes)
			(layer "F.SilkS")
			(hide yes)
			(effects
				(font
					(size 0.762 0.762)
					(thickness 0.2286)
				)
			)
		)
		(sheetname "POWER")
		(sheetfile "POWER.kicad_sch")
		(duplicate_pad_numbers_are_jumpers no)
		(pad "1" smd rect
			(at -0.4 0 90)
			(size 0.45 0.45)
			(layers "F.Cu" "F.Mask" "F.Paste")
			(net "+3.3V")
		)
		(pad "2" smd rect
			(at 0.4 0 90)
			(size 0.45 0.45)
			(layers "F.Cu" "F.Mask" "F.Paste")
			(net "NetR68_2")
		)
	)
	(footprint "Capacitors:CAPC1005X06N"
		(layer "B.Cu")
		(at 116.5781 151.7886 90)
		(property "Reference" "C45"
			(at 2.835 -0.445345 270)
			(unlocked yes)
			(layer "B.SilkS")
			(effects
				(font
					(size 0.762 0.762)
					(thickness 0.2286)
				)
				(justify left bottom mirror)
			)
		)
		(property "Value" "CAP_0402_0.1UF_50V"
			(at -3.382645 0.2921 0)
			(unlocked yes)
			(layer "B.SilkS")
			(hide yes)
			(effects
				(font
					(size 0.762 0.762)
					(thickness 0.2286)
				)
				(justify left bottom mirror)
			)
		)
		(sheetname "PCIe_JTAG")
		(sheetfile "PCIe_JTAG.kicad_sch")
		(duplicate_pad_numbers_are_jumpers no)
		(pad "1" smd rect
			(at -0.43 0)
			(size 0.64 0.68)
			(layers "B.Cu" "B.Mask" "B.Paste")
			(net "NetC45_1")
		)
		(pad "2" smd rect
			(at 0.43 0)
			(size 0.64 0.68)
			(layers "B.Cu" "B.Mask" "B.Paste")
			(net "PCIE_CLK_N")
		)
	)
	(footprint "Capacitors:CAPC1005X06N"
		(layer "B.Cu")
		(at 131.5641 151.7886 90)
		(property "Reference" "C52"
			(at 2.41349 -0.613855 270)
			(unlocked yes)
			(layer "B.SilkS")
			(effects
				(font
					(size 0.762 0.762)
					(thickness 0.2286)
				)
				(justify left bottom mirror)
			)
		)
		(property "Value" "CAP_0402_0.1UF_50V"
			(at -3.382645 0.2921 0)
			(unlocked yes)
			(layer "B.SilkS")
			(hide yes)
			(effects
				(font
					(size 0.762 0.762)
					(thickness 0.2286)
				)
				(justify left bottom mirror)
			)
		)
		(sheetname "PCIe_JTAG")
		(sheetfile "PCIe_JTAG.kicad_sch")
		(duplicate_pad_numbers_are_jumpers no)
		(pad "1" smd rect
			(at -0.43 0)
			(size 0.64 0.68)
			(layers "B.Cu" "B.Mask" "B.Paste")
			(net "NetC52_1")
		)
		(pad "2" smd rect
			(at 0.43 0)
			(size 0.64 0.68)
			(layers "B.Cu" "B.Mask" "B.Paste")
			(net "PCIE_TX3_P")
		)
	)
	(footprint "Capacitors:CAPC1005X06N"
		(layer "B.Cu")
		(at 128.3891 151.7886 90)
		(property "Reference" "C51"
			(at 2.41349 0.148145 270)
			(unlocked yes)
			(layer "B.SilkS")
			(effects
				(font
					(size 0.762 0.762)
					(thickness 0.2286)
				)
				(justify left bottom mirror)
			)
		)
		(property "Value" "CAP_0402_0.1UF_50V"
			(at -3.382645 0.2921 0)
			(unlocked yes)
			(layer "B.SilkS")
			(hide yes)
			(effects
				(font
					(size 0.762 0.762)
					(thickness 0.2286)
				)
				(justify left bottom mirror)
			)
		)
		(sheetname "PCIe_JTAG")
		(sheetfile "PCIe_JTAG.kicad_sch")
		(duplicate_pad_numbers_are_jumpers no)
		(pad "1" smd rect
			(at -0.43 0)
			(size 0.64 0.68)
			(layers "B.Cu" "B.Mask" "B.Paste")
			(net "NetC51_1")
		)
		(pad "2" smd rect
			(at 0.43 0)
			(size 0.64 0.68)
			(layers "B.Cu" "B.Mask" "B.Paste")
			(net "PCIE_TX2_N")
		)
	)
	(footprint "Capacitors:CAPC1005X06N"
		(layer "B.Cu")
		(at 132.5801 151.7886 90)
		(property "Reference" "C53"
			(at 2.41349 0.046545 270)
			(unlocked yes)
			(layer "B.SilkS")
			(effects
				(font
					(size 0.762 0.762)
					(thickness 0.2286)
				)
				(justify left bottom mirror)
			)
		)
		(property "Value" "CAP_0402_0.1UF_50V"
			(at -3.382645 0.2921 0)
			(unlocked yes)
			(layer "B.SilkS")
			(hide yes)
			(effects
				(font
					(size 0.762 0.762)
					(thickness 0.2286)
				)
				(justify left bottom mirror)
			)
		)
		(sheetname "PCIe_JTAG")
		(sheetfile "PCIe_JTAG.kicad_sch")
		(duplicate_pad_numbers_are_jumpers no)
		(pad "1" smd rect
			(at -0.43 0)
			(size 0.64 0.68)
			(layers "B.Cu" "B.Mask" "B.Paste")
			(net "NetC53_1")
		)
		(pad "2" smd rect
			(at 0.43 0)
			(size 0.64 0.68)
			(layers "B.Cu" "B.Mask" "B.Paste")
			(net "PCIE_TX3_N")
		)
	)
)
